(kicad_pcb
	(version 20260206)
	(generator "pcbnew")
	(generator_version "10.0")
	(general
		(thickness 1.6)
		(legacy_teardrops no)
	)
	(paper "A4")
	(title_block
		(title "peb — Lightning_PEB_BRD.brd")
		(comment 1 "Lightning (Wiwynn / Facebook NVMe JBOF) / footprints 950-956 of 2563")
	)
	(layers
		(0 "F.Cu" signal "TOP")
		(4 "In1.Cu" signal "L2GND")
		(6 "In2.Cu" signal "L3")
		(8 "In3.Cu" signal "L4VCC")
		(10 "In4.Cu" signal "L5VCC")
		(12 "In5.Cu" signal "L6")
		(14 "In6.Cu" signal "L7GND")
		(2 "B.Cu" signal "BOTTOM")
		(9 "F.Adhes" user "F.Adhesive")
		(11 "B.Adhes" user "B.Adhesive")
		(13 "F.Paste" user "Package Geometry/Pastemask Top")
		(15 "B.Paste" user "Package Geometry/Pastemask Bottom")
		(5 "F.SilkS" user "Ref Des/Silkscreen Top")
		(7 "B.SilkS" user "Ref Des/Silkscreen Bottom")
		(1 "F.Mask" user "Board Geometry/Soldermask Top")
		(3 "B.Mask" user "Board Geometry/Soldermask Bottom")
		(17 "Dwgs.User" user "User.Drawings")
		(19 "Cmts.User" user "User.Comments")
		(21 "Eco1.User" user "User.Eco1")
		(23 "Eco2.User" user "User.Eco2")
		(25 "Edge.Cuts" user "Board Geometry/Outline")
		(27 "Margin" user)
		(31 "F.CrtYd" user "Package Geometry/Place Bound Top")
		(29 "B.CrtYd" user "Package Geometry/Place Bound Bottom")
		(35 "F.Fab" user "Ref Des/Assembly Top")
		(33 "B.Fab" user "Ref Des/Assembly Bottom")
	)
	(footprint ""
		(layer "F.Cu")
		(at 142.247874 -85.08492 -90)
		(property "Reference" "PR9033"
			(at 0 0 270)
			(layer "F.SilkS")
			(hide yes)
			(effects
				(font
					(size 1.27 1.27)
				)
			)
		)
		(property "Value" "3K65R2F-1-GP"
			(at 0.064008 -3.993896 270)
			(unlocked yes)
			(layer "F.Fab")
			(hide yes)
			(effects
				(font
					(size 1.016 1.016)
					(thickness 0.1524)
				)
			)
		)
		(property "Device Type" "R402H16"
			(at 0.064008 -5.517896 270)
			(unlocked yes)
			(layer "F.Fab")
			(hide yes)
			(effects
				(font
					(size 1.016 1.016)
					(thickness 0.1524)
				)
			)
		)
		(duplicate_pad_numbers_are_jumpers no)
		(fp_line
			(start -0.508 -0.9398)
			(end -0.508 0.9398)
			(stroke
				(width 0.1524)
				(type default)
			)
			(layer "F.SilkS")
		)
		(fp_line
			(start 0.508 -0.9398)
			(end -0.508 -0.9398)
			(stroke
				(width 0.1524)
				(type default)
			)
			(layer "F.SilkS")
		)
		(fp_rect
			(start -0.508 0.9398)
			(end 0.508 -0.9398)
			(stroke
				(width 0)
				(type default)
			)
			(fill no)
			(layer "F.CrtYd")
		)
		(fp_rect
			(start -0.508 0.9398)
			(end 0.508 -0.9398)
			(stroke
				(width 0)
				(type default)
			)
			(fill no)
			(layer "F.Fab")
		)
		(pad "1" smd custom
			(at 0 -0.4445 270)
			(size 0.1397 0.1397)
			(layers "F.Cu" "F.Mask" "F.Paste")
			(net "P1V8_PWR")
			(options
				(clearance outline)
				(anchor circle)
			)
			(primitives
				(gr_poly
					(pts
						(arc
							(start -0.1778 -0.2794)
							(mid -0.249642 -0.249642)
							(end -0.2794 -0.1778)
						)
						(arc
							(start -0.2794 0.1778)
							(mid -0.249642 0.249642)
							(end -0.1778 0.2794)
						)
						(arc
							(start 0.1778 0.2794)
							(mid 0.249642 0.249642)
							(end 0.2794 0.1778)
						)
						(arc
							(start 0.2794 -0.1778)
							(mid 0.249642 -0.249642)
							(end 0.1778 -0.2794)
						)
					)
					(width 0)
					(fill yes)
				)
			)
		)
		(pad "2" smd custom
			(at 0 0.4445 270)
			(size 0.1397 0.1397)
			(layers "F.Cu" "F.Mask" "F.Paste")
			(net "VR_P1V8_STBY_FB")
			(options
				(clearance outline)
				(anchor circle)
			)
			(primitives
				(gr_poly
					(pts
						(arc
							(start -0.1778 -0.2794)
							(mid -0.249642 -0.249642)
							(end -0.2794 -0.1778)
						)
						(arc
							(start -0.2794 0.1778)
							(mid -0.249642 0.249642)
							(end -0.1778 0.2794)
						)
						(arc
							(start 0.1778 0.2794)
							(mid 0.249642 0.249642)
							(end 0.2794 0.1778)
						)
						(arc
							(start 0.2794 -0.1778)
							(mid 0.249642 -0.249642)
							(end 0.1778 -0.2794)
						)
					)
					(width 0)
					(fill yes)
				)
			)
		)
	)
	(footprint ""
		(layer "F.Cu")
		(at 178.1048 -64.643 180)
		(property "Reference" "PG16"
			(at 0 0 180)
			(layer "F.SilkS")
			(hide yes)
			(effects
				(font
					(size 1.27 1.27)
				)
			)
		)
		(property "Value" "GAP-CLOSE-PWR-3-GP"
			(at 0.0254 -6.5786 180)
			(unlocked yes)
			(layer "F.Fab")
			(hide yes)
			(effects
				(font
					(size 1.016 1.016)
					(thickness 0.1524)
				)
			)
		)
		(property "Device Type" "GAP-CLOSE-PWR-3"
			(at 0.0254 -8.255 180)
			(unlocked yes)
			(layer "F.Fab")
			(hide yes)
			(effects
				(font
					(size 1.016 1.016)
					(thickness 0.1524)
				)
			)
		)
		(duplicate_pad_numbers_are_jumpers no)
		(fp_rect
			(start -0.7112 0.4572)
			(end 0.7112 -0.4572)
			(stroke
				(width 0)
				(type default)
			)
			(fill no)
			(layer "F.CrtYd")
		)
		(fp_poly
			(pts
				(xy -0.7112 -0.4572) (xy 0.7112 -0.4572) (xy 0.7112 0.4572) (xy -0.7112 0.4572)
			)
			(stroke
				(width 0)
				(type default)
			)
			(fill no)
			(layer "F.Fab")
		)
		(pad "1" smd rect
			(at -0.3048 0 180)
			(size 0.6604 0.762)
			(layers "F.Cu" "F.Mask" "F.Paste")
			(net "DUT_AVD_PCIE")
		)
		(pad "2" smd rect
			(at 0.3048 0 180)
			(size 0.6604 0.762)
			(layers "F.Cu" "F.Mask" "F.Paste")
			(net "P0V9")
		)
	)
	(footprint ""
		(layer "F.Cu")
		(at 209.868008 -4.064)
		(property "Reference" "R681"
			(at 0 0 0)
			(layer "F.SilkS")
			(hide yes)
			(effects
				(font
					(size 1.27 1.27)
				)
			)
		)
		(property "Value" "100KR2F-L1-GP"
			(at 0.064008 -3.993896 0)
			(unlocked yes)
			(layer "F.Fab")
			(hide yes)
			(effects
				(font
					(size 1.016 1.016)
					(thickness 0.1524)
				)
			)
		)
		(property "Device Type" "R402H16"
			(at 0.064008 -5.517896 0)
			(unlocked yes)
			(layer "F.Fab")
			(hide yes)
			(effects
				(font
					(size 1.016 1.016)
					(thickness 0.1524)
				)
			)
		)
		(duplicate_pad_numbers_are_jumpers no)
		(fp_line
			(start -0.508 -0.9398)
			(end -0.508 0.9398)
			(stroke
				(width 0.1524)
				(type default)
			)
			(layer "F.SilkS")
		)
		(fp_line
			(start 0.508 -0.9398)
			(end -0.508 -0.9398)
			(stroke
				(width 0.1524)
				(type default)
			)
			(layer "F.SilkS")
		)
		(fp_rect
			(start -0.508 0.9398)
			(end 0.508 -0.9398)
			(stroke
				(width 0)
				(type default)
			)
			(fill no)
			(layer "F.CrtYd")
		)
		(fp_rect
			(start -0.508 0.9398)
			(end 0.508 -0.9398)
			(stroke
				(width 0)
				(type default)
			)
			(fill no)
			(layer "F.Fab")
		)
		(pad "1" smd custom
			(at 0 -0.4445)
			(size 0.1397 0.1397)
			(layers "F.Cu" "F.Mask" "F.Paste")
			(net "HOST7_RST_N")
			(options
				(clearance outline)
				(anchor circle)
			)
			(primitives
				(gr_poly
					(pts
						(arc
							(start -0.1778 -0.2794)
							(mid -0.249642 -0.249642)
							(end -0.2794 -0.1778)
						)
						(arc
							(start -0.2794 0.1778)
							(mid -0.249642 0.249642)
							(end -0.1778 0.2794)
						)
						(arc
							(start 0.1778 0.2794)
							(mid 0.249642 0.249642)
							(end 0.2794 0.1778)
						)
						(arc
							(start 0.2794 -0.1778)
							(mid 0.249642 -0.249642)
							(end 0.1778 -0.2794)
						)
					)
					(width 0)
					(fill yes)
				)
			)
		)
		(pad "2" smd custom
			(at 0 0.4445)
			(size 0.1397 0.1397)
			(layers "F.Cu" "F.Mask" "F.Paste")
			(net "GND")
			(options
				(clearance outline)
				(anchor circle)
			)
			(primitives
				(gr_poly
					(pts
						(arc
							(start -0.1778 -0.2794)
							(mid -0.249642 -0.249642)
							(end -0.2794 -0.1778)
						)
						(arc
							(start -0.2794 0.1778)
							(mid -0.249642 0.249642)
							(end -0.1778 0.2794)
						)
						(arc
							(start 0.1778 0.2794)
							(mid 0.249642 0.249642)
							(end 0.2794 0.1778)
						)
						(arc
							(start 0.2794 -0.1778)
							(mid 0.249642 -0.249642)
							(end 0.1778 -0.2794)
						)
					)
					(width 0)
					(fill yes)
				)
			)
		)
	)
	(footprint ""
		(layer "F.Cu")
		(at 162.753802 -65.432432 90)
		(property "Reference" "PL11"
			(at 0 0 90)
			(layer "F.SilkS")
			(hide yes)
			(effects
				(font
					(size 1.27 1.27)
				)
			)
		)
		(property "Value" "IND-300NH-8-GP"
			(at -5.6769 -0.4572 90)
			(unlocked yes)
			(layer "F.Fab")
			(hide yes)
			(effects
				(font
					(size 1.016 1.016)
					(thickness 0.1524)
				)
			)
		)
		(property "Device Type" "L102078-254224H296"
			(at -5.6769 -1.9812 90)
			(unlocked yes)
			(layer "F.Fab")
			(hide yes)
			(effects
				(font
					(size 1.016 1.016)
					(thickness 0.1524)
				)
			)
		)
		(duplicate_pad_numbers_are_jumpers no)
		(fp_line
			(start 4.1529 -5.9944)
			(end -4.1529 -5.9944)
			(stroke
				(width 0.1524)
				(type default)
			)
			(layer "F.SilkS")
		)
		(fp_line
			(start -4.1529 -5.9944)
			(end -4.1529 5.9944)
			(stroke
				(width 0.1524)
				(type default)
			)
			(layer "F.SilkS")
		)
		(fp_line
			(start 4.1529 5.9944)
			(end 4.1529 -5.9944)
			(stroke
				(width 0.1524)
				(type default)
			)
			(layer "F.SilkS")
		)
		(fp_line
			(start -4.1529 5.9944)
			(end 4.1529 5.9944)
			(stroke
				(width 0.1524)
				(type default)
			)
			(layer "F.SilkS")
		)
		(fp_poly
			(pts
				(xy -3.8989 -5.1054) (xy -3.8989 5.1054) (xy 3.8989 5.1054) (xy 3.8989 -5.1054)
			)
			(stroke
				(width 0)
				(type default)
			)
			(fill no)
			(layer "F.CrtYd")
		)
		(fp_poly
			(pts
				(xy -3.8989 -5.1054) (xy 4.4069 -5.1054) (xy 4.4069 -6.0706) (xy -4.4069 -6.0706) (xy -4.4069 6.0706)
				(xy 4.4069 6.0706) (xy 4.4069 -5.0927) (xy 3.8989 -5.0927) (xy 3.8989 5.1054) (xy -3.8989 5.1054)
			)
			(stroke
				(width 0)
				(type default)
			)
			(fill no)
			(layer "F.CrtYd")
		)
		(fp_rect
			(start -4.4069 6.0706)
			(end 4.4069 -6.0706)
			(stroke
				(width 0)
				(type default)
			)
			(fill no)
			(layer "F.Fab")
		)
		(pad "1" smd rect
			(at 0 -4.020566 90)
			(size 2.4892 3.429)
			(layers "F.Cu" "F.Mask" "F.Paste")
			(net "P0V9_LX")
		)
		(pad "2" smd rect
			(at 0 4.020566 90)
			(size 2.4892 3.429)
			(layers "F.Cu" "F.Mask" "F.Paste")
			(net "P0V9")
		)
	)
	(footprint ""
		(layer "F.Cu")
		(at 144.8054 -51.816)
		(property "Reference" "R755"
			(at 0 0 0)
			(layer "F.SilkS")
			(hide yes)
			(effects
				(font
					(size 1.27 1.27)
				)
			)
		)
		(property "Value" "150R2F-1-GP"
			(at 0.064008 -3.993896 0)
			(unlocked yes)
			(layer "F.Fab")
			(hide yes)
			(effects
				(font
					(size 1.016 1.016)
					(thickness 0.1524)
				)
			)
		)
		(property "Device Type" "R402H16"
			(at 0.064008 -5.517896 0)
			(unlocked yes)
			(layer "F.Fab")
			(hide yes)
			(effects
				(font
					(size 1.016 1.016)
					(thickness 0.1524)
				)
			)
		)
		(duplicate_pad_numbers_are_jumpers no)
		(fp_line
			(start -0.508 -0.9398)
			(end -0.508 0.9398)
			(stroke
				(width 0.1524)
				(type default)
			)
			(layer "F.SilkS")
		)
		(fp_line
			(start 0.508 -0.9398)
			(end -0.508 -0.9398)
			(stroke
				(width 0.1524)
				(type default)
			)
			(layer "F.SilkS")
		)
		(fp_rect
			(start -0.508 0.9398)
			(end 0.508 -0.9398)
			(stroke
				(width 0)
				(type default)
			)
			(fill no)
			(layer "F.CrtYd")
		)
		(fp_rect
			(start -0.508 0.9398)
			(end 0.508 -0.9398)
			(stroke
				(width 0)
				(type default)
			)
			(fill no)
			(layer "F.Fab")
		)
		(pad "1" smd custom
			(at 0 -0.4445)
			(size 0.1397 0.1397)
			(layers "F.Cu" "F.Mask" "F.Paste")
			(net "DUT_VDDO")
			(options
				(clearance outline)
				(anchor circle)
			)
			(primitives
				(gr_poly
					(pts
						(arc
							(start -0.1778 -0.2794)
							(mid -0.249642 -0.249642)
							(end -0.2794 -0.1778)
						)
						(arc
							(start -0.2794 0.1778)
							(mid -0.249642 0.249642)
							(end -0.1778 0.2794)
						)
						(arc
							(start 0.1778 0.2794)
							(mid 0.249642 0.249642)
							(end 0.2794 0.1778)
						)
						(arc
							(start 0.2794 -0.1778)
							(mid 0.249642 -0.249642)
							(end 0.1778 -0.2794)
						)
					)
					(width 0)
					(fill yes)
				)
			)
		)
		(pad "2" smd custom
			(at 0 0.4445)
			(size 0.1397 0.1397)
			(layers "F.Cu" "F.Mask" "F.Paste")
			(net "EJTAG_PWR")
			(options
				(clearance outline)
				(anchor circle)
			)
			(primitives
				(gr_poly
					(pts
						(arc
							(start -0.1778 -0.2794)
							(mid -0.249642 -0.249642)
							(end -0.2794 -0.1778)
						)
						(arc
							(start -0.2794 0.1778)
							(mid -0.249642 0.249642)
							(end -0.1778 0.2794)
						)
						(arc
							(start 0.1778 0.2794)
							(mid 0.249642 0.249642)
							(end 0.2794 0.1778)
						)
						(arc
							(start 0.2794 -0.1778)
							(mid 0.249642 -0.249642)
							(end 0.1778 -0.2794)
						)
					)
					(width 0)
					(fill yes)
				)
			)
		)
	)
	(footprint ""
		(layer "F.Cu")
		(at 50.5206 -69.690488)
		(property "Reference" "SCN8"
			(at 0 0 0)
			(layer "F.SilkS")
			(hide yes)
			(effects
				(font
					(size 1.27 1.27)
				)
			)
		)
		(property "Value" "JWT-CON4-S24-GP"
			(at -7.3787 1.4351 0)
			(unlocked yes)
			(layer "F.Fab")
			(hide yes)
			(effects
				(font
					(size 1.016 1.016)
					(thickness 0.1524)
				)
			)
		)
		(property "Device Type" "A2541WV0-1QX4PA-6T"
			(at -7.3787 -0.0889 0)
			(unlocked yes)
			(layer "F.Fab")
			(hide yes)
			(effects
				(font
					(size 1.016 1.016)
					(thickness 0.1524)
				)
			)
		)
		(duplicate_pad_numbers_are_jumpers no)
		(fp_line
			(start -5.461 -1.651)
			(end -5.461 -0.381)
			(stroke
				(width 0.4064)
				(type default)
			)
			(layer "F.SilkS")
		)
		(fp_line
			(start -5.334 -1.524)
			(end -5.334 1.524)
			(stroke
				(width 0.1524)
				(type default)
			)
			(layer "F.SilkS")
		)
		(fp_line
			(start -5.334 1.524)
			(end 5.334 1.524)
			(stroke
				(width 0.1524)
				(type default)
			)
			(layer "F.SilkS")
		)
		(fp_line
			(start -4.191 -1.651)
			(end -5.461 -1.651)
			(stroke
				(width 0.4064)
				(type default)
			)
			(layer "F.SilkS")
		)
		(fp_line
			(start 5.334 -1.524)
			(end -5.334 -1.524)
			(stroke
				(width 0.1524)
				(type default)
			)
			(layer "F.SilkS")
		)
		(fp_line
			(start 5.334 1.524)
			(end 5.334 -1.524)
			(stroke
				(width 0.1524)
				(type default)
			)
			(layer "F.SilkS")
		)
		(fp_circle
			(center -3.81 0)
			(end -2.7432 0)
			(stroke
				(width 0.3048)
				(type default)
			)
			(fill no)
			(layer "F.SilkS")
		)
		(fp_circle
			(center -1.27 0)
			(end -0.2032 0)
			(stroke
				(width 0.3048)
				(type default)
			)
			(fill no)
			(layer "F.SilkS")
		)
		(fp_circle
			(center 1.27 0)
			(end 2.3368 0)
			(stroke
				(width 0.3048)
				(type default)
			)
			(fill no)
			(layer "F.SilkS")
		)
		(fp_circle
			(center 3.81 0)
			(end 4.8768 0)
			(stroke
				(width 0.3048)
				(type default)
			)
			(fill no)
			(layer "F.SilkS")
		)
		(fp_rect
			(start -5.08 1.27)
			(end 5.08 -1.27)
			(stroke
				(width 0)
				(type default)
			)
			(fill no)
			(layer "F.CrtYd")
		)
		(fp_poly
			(pts
				(xy -5.588 1.778) (xy -5.588 -1.778) (xy 5.588 -1.778) (xy 5.588 1.2573) (xy 5.08 1.2573) (xy 5.08 -1.27)
				(xy -5.08 -1.27) (xy -5.08 1.27) (xy 5.588 1.27) (xy 5.588 1.778)
			)
			(stroke
				(width 0)
				(type default)
			)
			(fill no)
			(layer "F.CrtYd")
		)
		(fp_rect
			(start -5.588 1.778)
			(end 5.588 -1.778)
			(stroke
				(width 0)
				(type default)
			)
			(fill no)
			(layer "F.Fab")
		)
		(pad "1" thru_hole circle
			(at -3.81 0)
			(size 1.4224 1.4224)
			(drill 1.016)
			(layers "*.Cu" "*.Mask")
			(remove_unused_layers no)
			(net "P5V_STBY")
			(clearance 0.1524)
			(thermal_gap 0.1524)
		)
		(pad "2" thru_hole circle
			(at -1.27 0)
			(size 1.4224 1.4224)
			(drill 1.016)
			(layers "*.Cu" "*.Mask")
			(remove_unused_layers no)
			(net "BMC_R_TXD5")
			(clearance 0.1524)
			(thermal_gap 0.1524)
		)
		(pad "3" thru_hole circle
			(at 1.27 0)
			(size 1.4224 1.4224)
			(drill 1.016)
			(layers "*.Cu" "*.Mask")
			(remove_unused_layers no)
			(net "BMC_R_RXD5")
			(clearance 0.1524)
			(thermal_gap 0.1524)
		)
		(pad "4" thru_hole circle
			(at 3.81 0)
			(size 1.4224 1.4224)
			(drill 1.016)
			(layers "*.Cu" "*.Mask")
			(remove_unused_layers no)
			(net "GND")
			(clearance 0.1524)
			(thermal_gap 0.1524)
		)
	)
	(footprint ""
		(layer "F.Cu")
		(at 332.7908 -184.8866)
		(property "Reference" "R563"
			(at 0 0 0)
			(layer "F.SilkS")
			(hide yes)
			(effects
				(font
					(size 1.27 1.27)
				)
			)
		)
		(property "Value" "10KR2F-2-GP"
			(at 0.064008 -3.993896 0)
			(unlocked yes)
			(layer "F.Fab")
			(hide yes)
			(effects
				(font
					(size 1.016 1.016)
					(thickness 0.1524)
				)
			)
		)
		(property "Device Type" "R402H16"
			(at 0.064008 -5.517896 0)
			(unlocked yes)
			(layer "F.Fab")
			(hide yes)
			(effects
				(font
					(size 1.016 1.016)
					(thickness 0.1524)
				)
			)
		)
		(duplicate_pad_numbers_are_jumpers no)
		(fp_line
			(start -0.508 -0.9398)
			(end -0.508 0.9398)
			(stroke
				(width 0.1524)
				(type default)
			)
			(layer "F.SilkS")
		)
		(fp_line
			(start 0.508 -0.9398)
			(end -0.508 -0.9398)
			(stroke
				(width 0.1524)
				(type default)
			)
			(layer "F.SilkS")
		)
		(fp_rect
			(start -0.508 0.9398)
			(end 0.508 -0.9398)
			(stroke
				(width 0)
				(type default)
			)
			(fill no)
			(layer "F.CrtYd")
		)
		(fp_rect
			(start -0.508 0.9398)
			(end 0.508 -0.9398)
			(stroke
				(width 0)
				(type default)
			)
			(fill no)
			(layer "F.Fab")
		)
		(pad "1" smd custom
			(at 0 -0.4445)
			(size 0.1397 0.1397)
			(layers "F.Cu" "F.Mask" "F.Paste")
			(net "GND")
			(options
				(clearance outline)
				(anchor circle)
			)
			(primitives
				(gr_poly
					(pts
						(arc
							(start -0.1778 -0.2794)
							(mid -0.249642 -0.249642)
							(end -0.2794 -0.1778)
						)
						(arc
							(start -0.2794 0.1778)
							(mid -0.249642 0.249642)
							(end -0.1778 0.2794)
						)
						(arc
							(start 0.1778 0.2794)
							(mid 0.249642 0.249642)
							(end 0.2794 0.1778)
						)
						(arc
							(start 0.2794 -0.1778)
							(mid 0.249642 -0.249642)
							(end 0.1778 -0.2794)
						)
					)
					(width 0)
					(fill yes)
				)
			)
		)
		(pad "2" smd custom
			(at 0 0.4445)
			(size 0.1397 0.1397)
			(layers "F.Cu" "F.Mask" "F.Paste")
			(net "IOEXP4_AD0")
			(options
				(clearance outline)
				(anchor circle)
			)
			(primitives
				(gr_poly
					(pts
						(arc
							(start -0.1778 -0.2794)
							(mid -0.249642 -0.249642)
							(end -0.2794 -0.1778)
						)
						(arc
							(start -0.2794 0.1778)
							(mid -0.249642 0.249642)
							(end -0.1778 0.2794)
						)
						(arc
							(start 0.1778 0.2794)
							(mid 0.249642 0.249642)
							(end 0.2794 0.1778)
						)
						(arc
							(start 0.2794 -0.1778)
							(mid 0.249642 -0.249642)
							(end 0.1778 -0.2794)
						)
					)
					(width 0)
					(fill yes)
				)
			)
		)
	)
)
